(kicad_pcb
	(version 20260206)
	(generator "pcbnew")
	(generator_version "10.0")
	(general
		(thickness 1.6)
		(legacy_teardrops no)
	)
	(paper "A4")
	(title_block
		(title "peb — Lightning_PEB_BRD.brd")
		(comment 1 "Lightning (Wiwynn / Facebook NVMe JBOF) / footprints 529-536 of 2563")
	)
	(layers
		(0 "F.Cu" signal "TOP")
		(4 "In1.Cu" signal "L2GND")
		(6 "In2.Cu" signal "L3")
		(8 "In3.Cu" signal "L4VCC")
		(10 "In4.Cu" signal "L5VCC")
		(12 "In5.Cu" signal "L6")
		(14 "In6.Cu" signal "L7GND")
		(2 "B.Cu" signal "BOTTOM")
		(9 "F.Adhes" user "F.Adhesive")
		(11 "B.Adhes" user "B.Adhesive")
		(13 "F.Paste" user "Package Geometry/Pastemask Top")
		(15 "B.Paste" user "Package Geometry/Pastemask Bottom")
		(5 "F.SilkS" user "Ref Des/Silkscreen Top")
		(7 "B.SilkS" user "Ref Des/Silkscreen Bottom")
		(1 "F.Mask" user "Board Geometry/Soldermask Top")
		(3 "B.Mask" user "Board Geometry/Soldermask Bottom")
		(17 "Dwgs.User" user "User.Drawings")
		(19 "Cmts.User" user "User.Comments")
		(21 "Eco1.User" user "User.Eco1")
		(23 "Eco2.User" user "User.Eco2")
		(25 "Edge.Cuts" user "Board Geometry/Outline")
		(27 "Margin" user)
		(31 "F.CrtYd" user "Package Geometry/Place Bound Top")
		(29 "B.CrtYd" user "Package Geometry/Place Bound Bottom")
		(35 "F.Fab" user "Ref Des/Assembly Top")
		(33 "B.Fab" user "Ref Des/Assembly Bottom")
	)
	(footprint ""
		(layer "F.Cu")
		(at 228.3968 -16.1036 180)
		(property "Reference" "R7909"
			(at 0 0 180)
			(layer "F.SilkS")
			(hide yes)
			(effects
				(font
					(size 1.27 1.27)
				)
			)
		)
		(property "Value" "0R2J-2-GP"
			(at 0.064008 -3.993896 180)
			(unlocked yes)
			(layer "F.Fab")
			(hide yes)
			(effects
				(font
					(size 1.016 1.016)
					(thickness 0.1524)
				)
			)
		)
		(property "Device Type" "R402H16"
			(at 0.064008 -5.517896 180)
			(unlocked yes)
			(layer "F.Fab")
			(hide yes)
			(effects
				(font
					(size 1.016 1.016)
					(thickness 0.1524)
				)
			)
		)
		(duplicate_pad_numbers_are_jumpers no)
		(fp_line
			(start 0.508 -0.9398)
			(end -0.508 -0.9398)
			(stroke
				(width 0.1524)
				(type default)
			)
			(layer "F.SilkS")
		)
		(fp_line
			(start -0.508 -0.9398)
			(end -0.508 0.9398)
			(stroke
				(width 0.1524)
				(type default)
			)
			(layer "F.SilkS")
		)
		(fp_rect
			(start -0.508 0.9398)
			(end 0.508 -0.9398)
			(stroke
				(width 0)
				(type default)
			)
			(fill no)
			(layer "F.CrtYd")
		)
		(fp_rect
			(start -0.508 0.9398)
			(end 0.508 -0.9398)
			(stroke
				(width 0)
				(type default)
			)
			(fill no)
			(layer "F.Fab")
		)
		(pad "1" smd custom
			(at 0 -0.4445 180)
			(size 0.1397 0.1397)
			(layers "F.Cu" "F.Mask" "F.Paste")
			(net "U82_RST#")
			(options
				(clearance outline)
				(anchor circle)
			)
			(primitives
				(gr_poly
					(pts
						(arc
							(start -0.1778 -0.2794)
							(mid -0.249642 -0.249642)
							(end -0.2794 -0.1778)
						)
						(arc
							(start -0.2794 0.1778)
							(mid -0.249642 0.249642)
							(end -0.1778 0.2794)
						)
						(arc
							(start 0.1778 0.2794)
							(mid 0.249642 0.249642)
							(end 0.2794 0.1778)
						)
						(arc
							(start 0.2794 -0.1778)
							(mid 0.249642 -0.249642)
							(end 0.1778 -0.2794)
						)
					)
					(width 0)
					(fill yes)
				)
			)
		)
		(pad "2" smd custom
			(at 0 0.4445 180)
			(size 0.1397 0.1397)
			(layers "F.Cu" "F.Mask" "F.Paste")
			(net "HOST1_RST_N_LS")
			(options
				(clearance outline)
				(anchor circle)
			)
			(primitives
				(gr_poly
					(pts
						(arc
							(start -0.1778 -0.2794)
							(mid -0.249642 -0.249642)
							(end -0.2794 -0.1778)
						)
						(arc
							(start -0.2794 0.1778)
							(mid -0.249642 0.249642)
							(end -0.1778 0.2794)
						)
						(arc
							(start 0.1778 0.2794)
							(mid 0.249642 0.249642)
							(end 0.2794 0.1778)
						)
						(arc
							(start 0.2794 -0.1778)
							(mid 0.249642 -0.249642)
							(end 0.1778 -0.2794)
						)
					)
					(width 0)
					(fill yes)
				)
			)
		)
	)
	(footprint ""
		(layer "F.Cu")
		(at 170.60799 -212.420454 180)
		(property "Reference" "C141"
			(at 0 0 180)
			(layer "F.SilkS")
			(hide yes)
			(effects
				(font
					(size 1.27 1.27)
				)
			)
		)
		(property "Value" "SCD22U10V2KX-1GP"
			(at 1.1811 -2.7051 180)
			(unlocked yes)
			(layer "F.Fab")
			(hide yes)
			(effects
				(font
					(size 1.016 1.016)
					(thickness 0.1524)
				)
			)
		)
		(property "Device Type" "C402H22"
			(at 1.1811 -4.2291 180)
			(unlocked yes)
			(layer "F.Fab")
			(hide yes)
			(effects
				(font
					(size 1.016 1.016)
					(thickness 0.1524)
				)
			)
		)
		(duplicate_pad_numbers_are_jumpers no)
		(fp_rect
			(start -0.4318 0.9525)
			(end 0.4318 -0.9525)
			(stroke
				(width 0)
				(type default)
			)
			(fill no)
			(layer "F.CrtYd")
		)
		(fp_rect
			(start -0.4318 0.9525)
			(end 0.4318 -0.9525)
			(stroke
				(width 0)
				(type default)
			)
			(fill no)
			(layer "F.Fab")
		)
		(pad "1" smd custom
			(at 0 -0.4445 180)
			(size 0.1524 0.1524)
			(layers "F.Cu" "F.Mask" "F.Paste")
			(net "PCIE_TX_CAP_N50")
			(options
				(clearance outline)
				(anchor circle)
			)
			(primitives
				(gr_poly
					(pts
						(arc
							(start 0.3048 -0.2032)
							(mid 0.275042 -0.275042)
							(end 0.2032 -0.3048)
						)
						(arc
							(start -0.2032 -0.3048)
							(mid -0.275042 -0.275042)
							(end -0.3048 -0.2032)
						)
						(arc
							(start -0.3048 0.2032)
							(mid -0.275042 0.275042)
							(end -0.2032 0.3048)
						)
						(arc
							(start 0.2032 0.3048)
							(mid 0.275042 0.275042)
							(end 0.3048 0.2032)
						)
					)
					(width 0)
					(fill yes)
				)
			)
		)
		(pad "2" smd custom
			(at 0 0.4445 180)
			(size 0.1524 0.1524)
			(layers "F.Cu" "F.Mask" "F.Paste")
			(net "PCIE_TX_N50")
			(options
				(clearance outline)
				(anchor circle)
			)
			(primitives
				(gr_poly
					(pts
						(arc
							(start 0.3048 -0.2032)
							(mid 0.275042 -0.275042)
							(end 0.2032 -0.3048)
						)
						(arc
							(start -0.2032 -0.3048)
							(mid -0.275042 -0.275042)
							(end -0.3048 -0.2032)
						)
						(arc
							(start -0.3048 0.2032)
							(mid -0.275042 0.275042)
							(end -0.2032 0.3048)
						)
						(arc
							(start 0.2032 0.3048)
							(mid 0.275042 0.275042)
							(end 0.3048 0.2032)
						)
					)
					(width 0)
					(fill yes)
				)
			)
		)
	)
	(footprint ""
		(layer "F.Cu")
		(at 49.911 -198.247 -90)
		(property "Reference" "C702"
			(at 0 0 270)
			(layer "F.SilkS")
			(hide yes)
			(effects
				(font
					(size 1.27 1.27)
				)
			)
		)
		(property "Value" "SC220P50V3JN-GP"
			(at 0 -2.8194 270)
			(unlocked yes)
			(layer "F.Fab")
			(hide yes)
			(effects
				(font
					(size 1.016 1.016)
					(thickness 0.1524)
				)
			)
		)
		(property "Device Type" "C603H36"
			(at 0 -4.3434 270)
			(unlocked yes)
			(layer "F.Fab")
			(hide yes)
			(effects
				(font
					(size 1.016 1.016)
					(thickness 0.1524)
				)
			)
		)
		(duplicate_pad_numbers_are_jumpers no)
		(fp_line
			(start 0.508 0)
			(end -0.508 0)
			(stroke
				(width 0.2032)
				(type default)
			)
			(layer "F.SilkS")
		)
		(fp_rect
			(start -0.5842 1.3335)
			(end 0.5842 -1.3335)
			(stroke
				(width 0)
				(type default)
			)
			(fill no)
			(layer "F.CrtYd")
		)
		(fp_rect
			(start -0.5842 1.3335)
			(end 0.5842 -1.3335)
			(stroke
				(width 0)
				(type default)
			)
			(fill no)
			(layer "F.Fab")
		)
		(pad "1" smd custom
			(at 0 -0.762 270)
			(size 0.2159 0.2159)
			(layers "F.Cu" "F.Mask" "F.Paste")
			(net "BUF_I2C7_B_DPB_SDA_R")
			(options
				(clearance outline)
				(anchor circle)
			)
			(primitives
				(gr_poly
					(pts
						(arc
							(start -0.3302 -0.4318)
							(mid -0.402042 -0.402042)
							(end -0.4318 -0.3302)
						)
						(arc
							(start -0.4318 0.3302)
							(mid -0.402042 0.402042)
							(end -0.3302 0.4318)
						)
						(arc
							(start 0.3302 0.4318)
							(mid 0.402042 0.402042)
							(end 0.4318 0.3302)
						)
						(arc
							(start 0.4318 -0.3302)
							(mid 0.402042 -0.402042)
							(end 0.3302 -0.4318)
						)
					)
					(width 0)
					(fill yes)
				)
			)
		)
		(pad "2" smd custom
			(at 0 0.762 270)
			(size 0.2159 0.2159)
			(layers "F.Cu" "F.Mask" "F.Paste")
			(net "GND")
			(options
				(clearance outline)
				(anchor circle)
			)
			(primitives
				(gr_poly
					(pts
						(arc
							(start -0.3302 -0.4318)
							(mid -0.402042 -0.402042)
							(end -0.4318 -0.3302)
						)
						(arc
							(start -0.4318 0.3302)
							(mid -0.402042 0.402042)
							(end -0.3302 0.4318)
						)
						(arc
							(start 0.3302 0.4318)
							(mid 0.402042 0.402042)
							(end 0.4318 0.3302)
						)
						(arc
							(start 0.4318 -0.3302)
							(mid 0.402042 -0.402042)
							(end 0.3302 -0.4318)
						)
					)
					(width 0)
					(fill yes)
				)
			)
		)
	)
	(footprint ""
		(layer "F.Cu")
		(at 264.392156 -212.420454 180)
		(property "Reference" "C107"
			(at 0 0 180)
			(layer "F.SilkS")
			(hide yes)
			(effects
				(font
					(size 1.27 1.27)
				)
			)
		)
		(property "Value" "SCD22U10V2KX-1GP"
			(at 1.1811 -2.7051 180)
			(unlocked yes)
			(layer "F.Fab")
			(hide yes)
			(effects
				(font
					(size 1.016 1.016)
					(thickness 0.1524)
				)
			)
		)
		(property "Device Type" "C402H22"
			(at 1.1811 -4.2291 180)
			(unlocked yes)
			(layer "F.Fab")
			(hide yes)
			(effects
				(font
					(size 1.016 1.016)
					(thickness 0.1524)
				)
			)
		)
		(duplicate_pad_numbers_are_jumpers no)
		(fp_rect
			(start -0.4318 0.9525)
			(end 0.4318 -0.9525)
			(stroke
				(width 0)
				(type default)
			)
			(fill no)
			(layer "F.CrtYd")
		)
		(fp_rect
			(start -0.4318 0.9525)
			(end 0.4318 -0.9525)
			(stroke
				(width 0)
				(type default)
			)
			(fill no)
			(layer "F.Fab")
		)
		(pad "1" smd custom
			(at 0 -0.4445 180)
			(size 0.1524 0.1524)
			(layers "F.Cu" "F.Mask" "F.Paste")
			(net "PCIE_TX_CAP_P37")
			(options
				(clearance outline)
				(anchor circle)
			)
			(primitives
				(gr_poly
					(pts
						(arc
							(start 0.3048 -0.2032)
							(mid 0.275042 -0.275042)
							(end 0.2032 -0.3048)
						)
						(arc
							(start -0.2032 -0.3048)
							(mid -0.275042 -0.275042)
							(end -0.3048 -0.2032)
						)
						(arc
							(start -0.3048 0.2032)
							(mid -0.275042 0.275042)
							(end -0.2032 0.3048)
						)
						(arc
							(start 0.2032 0.3048)
							(mid 0.275042 0.275042)
							(end 0.3048 0.2032)
						)
					)
					(width 0)
					(fill yes)
				)
			)
		)
		(pad "2" smd custom
			(at 0 0.4445 180)
			(size 0.1524 0.1524)
			(layers "F.Cu" "F.Mask" "F.Paste")
			(net "PCIE_TX_P37")
			(options
				(clearance outline)
				(anchor circle)
			)
			(primitives
				(gr_poly
					(pts
						(arc
							(start 0.3048 -0.2032)
							(mid 0.275042 -0.275042)
							(end 0.2032 -0.3048)
						)
						(arc
							(start -0.2032 -0.3048)
							(mid -0.275042 -0.275042)
							(end -0.3048 -0.2032)
						)
						(arc
							(start -0.3048 0.2032)
							(mid -0.275042 0.275042)
							(end -0.2032 0.3048)
						)
						(arc
							(start 0.2032 0.3048)
							(mid 0.275042 0.275042)
							(end 0.3048 0.2032)
						)
					)
					(width 0)
					(fill yes)
				)
			)
		)
	)
	(footprint ""
		(layer "F.Cu")
		(at 33.6296 -186.7662 180)
		(property "Reference" "C258"
			(at 0 0 180)
			(layer "F.SilkS")
			(hide yes)
			(effects
				(font
					(size 1.27 1.27)
				)
			)
		)
		(property "Value" "SC220P50V3JN-GP"
			(at 0 -2.8194 180)
			(unlocked yes)
			(layer "F.Fab")
			(hide yes)
			(effects
				(font
					(size 1.016 1.016)
					(thickness 0.1524)
				)
			)
		)
		(property "Device Type" "C603H36"
			(at 0 -4.3434 180)
			(unlocked yes)
			(layer "F.Fab")
			(hide yes)
			(effects
				(font
					(size 1.016 1.016)
					(thickness 0.1524)
				)
			)
		)
		(duplicate_pad_numbers_are_jumpers no)
		(fp_line
			(start 0.508 0)
			(end -0.508 0)
			(stroke
				(width 0.2032)
				(type default)
			)
			(layer "F.SilkS")
		)
		(fp_rect
			(start -0.5842 1.3335)
			(end 0.5842 -1.3335)
			(stroke
				(width 0)
				(type default)
			)
			(fill no)
			(layer "F.CrtYd")
		)
		(fp_rect
			(start -0.5842 1.3335)
			(end 0.5842 -1.3335)
			(stroke
				(width 0)
				(type default)
			)
			(fill no)
			(layer "F.Fab")
		)
		(pad "1" smd custom
			(at 0 -0.762 180)
			(size 0.2159 0.2159)
			(layers "F.Cu" "F.Mask" "F.Paste")
			(net "BUF_I2C5_SCL_R")
			(options
				(clearance outline)
				(anchor circle)
			)
			(primitives
				(gr_poly
					(pts
						(arc
							(start -0.3302 -0.4318)
							(mid -0.402042 -0.402042)
							(end -0.4318 -0.3302)
						)
						(arc
							(start -0.4318 0.3302)
							(mid -0.402042 0.402042)
							(end -0.3302 0.4318)
						)
						(arc
							(start 0.3302 0.4318)
							(mid 0.402042 0.402042)
							(end 0.4318 0.3302)
						)
						(arc
							(start 0.4318 -0.3302)
							(mid 0.402042 -0.402042)
							(end 0.3302 -0.4318)
						)
					)
					(width 0)
					(fill yes)
				)
			)
		)
		(pad "2" smd custom
			(at 0 0.762 180)
			(size 0.2159 0.2159)
			(layers "F.Cu" "F.Mask" "F.Paste")
			(net "GND")
			(options
				(clearance outline)
				(anchor circle)
			)
			(primitives
				(gr_poly
					(pts
						(arc
							(start -0.3302 -0.4318)
							(mid -0.402042 -0.402042)
							(end -0.4318 -0.3302)
						)
						(arc
							(start -0.4318 0.3302)
							(mid -0.402042 0.402042)
							(end -0.3302 0.4318)
						)
						(arc
							(start 0.3302 0.4318)
							(mid 0.402042 0.402042)
							(end 0.4318 0.3302)
						)
						(arc
							(start 0.4318 -0.3302)
							(mid 0.402042 -0.402042)
							(end 0.3302 -0.4318)
						)
					)
					(width 0)
					(fill yes)
				)
			)
		)
	)
	(footprint ""
		(layer "F.Cu")
		(at 37.211 -202.565 180)
		(property "Reference" "R877"
			(at 0 0 180)
			(layer "F.SilkS")
			(hide yes)
			(effects
				(font
					(size 1.27 1.27)
				)
			)
		)
		(property "Value" "10KR2F-2-GP"
			(at 0.064008 -3.993896 180)
			(unlocked yes)
			(layer "F.Fab")
			(hide yes)
			(effects
				(font
					(size 1.016 1.016)
					(thickness 0.1524)
				)
			)
		)
		(property "Device Type" "R402H16"
			(at 0.064008 -5.517896 180)
			(unlocked yes)
			(layer "F.Fab")
			(hide yes)
			(effects
				(font
					(size 1.016 1.016)
					(thickness 0.1524)
				)
			)
		)
		(duplicate_pad_numbers_are_jumpers no)
		(fp_line
			(start 0.508 -0.9398)
			(end -0.508 -0.9398)
			(stroke
				(width 0.1524)
				(type default)
			)
			(layer "F.SilkS")
		)
		(fp_line
			(start -0.508 -0.9398)
			(end -0.508 0.9398)
			(stroke
				(width 0.1524)
				(type default)
			)
			(layer "F.SilkS")
		)
		(fp_rect
			(start -0.508 0.9398)
			(end 0.508 -0.9398)
			(stroke
				(width 0)
				(type default)
			)
			(fill no)
			(layer "F.CrtYd")
		)
		(fp_rect
			(start -0.508 0.9398)
			(end 0.508 -0.9398)
			(stroke
				(width 0)
				(type default)
			)
			(fill no)
			(layer "F.Fab")
		)
		(pad "1" smd custom
			(at 0 -0.4445 180)
			(size 0.1397 0.1397)
			(layers "F.Cu" "F.Mask" "F.Paste")
			(net "I2C6_BUF_READY")
			(options
				(clearance outline)
				(anchor circle)
			)
			(primitives
				(gr_poly
					(pts
						(arc
							(start -0.1778 -0.2794)
							(mid -0.249642 -0.249642)
							(end -0.2794 -0.1778)
						)
						(arc
							(start -0.2794 0.1778)
							(mid -0.249642 0.249642)
							(end -0.1778 0.2794)
						)
						(arc
							(start 0.1778 0.2794)
							(mid 0.249642 0.249642)
							(end 0.2794 0.1778)
						)
						(arc
							(start 0.2794 -0.1778)
							(mid 0.249642 -0.249642)
							(end 0.1778 -0.2794)
						)
					)
					(width 0)
					(fill yes)
				)
			)
		)
		(pad "2" smd custom
			(at 0 0.4445 180)
			(size 0.1397 0.1397)
			(layers "F.Cu" "F.Mask" "F.Paste")
			(net "P3V3_STBY")
			(options
				(clearance outline)
				(anchor circle)
			)
			(primitives
				(gr_poly
					(pts
						(arc
							(start -0.1778 -0.2794)
							(mid -0.249642 -0.249642)
							(end -0.2794 -0.1778)
						)
						(arc
							(start -0.2794 0.1778)
							(mid -0.249642 0.249642)
							(end -0.1778 0.2794)
						)
						(arc
							(start 0.1778 0.2794)
							(mid 0.249642 0.249642)
							(end 0.2794 0.1778)
						)
						(arc
							(start 0.2794 -0.1778)
							(mid 0.249642 -0.249642)
							(end 0.1778 -0.2794)
						)
					)
					(width 0)
					(fill yes)
				)
			)
		)
	)
	(footprint ""
		(layer "F.Cu")
		(at 32.639 -115.824)
		(property "Reference" "TP244"
			(at 0 0 0)
			(layer "F.SilkS")
			(hide yes)
			(effects
				(font
					(size 1.27 1.27)
				)
			)
		)
		(property "Value" "TPAD28-2-GP"
			(at -0.0127 -1.6637 0)
			(unlocked yes)
			(layer "F.Fab")
			(hide yes)
			(effects
				(font
					(size 1.016 1.016)
					(thickness 0.1524)
				)
			)
		)
		(property "Device Type" "TPAD28"
			(at -0.0127 -3.1877 0)
			(unlocked yes)
			(layer "F.Fab")
			(hide yes)
			(effects
				(font
					(size 1.016 1.016)
					(thickness 0.1524)
				)
			)
		)
		(duplicate_pad_numbers_are_jumpers no)
		(fp_poly
			(pts
				(arc
					(start 0.3556 0)
					(mid -0.3556 0)
					(end 0.3556 0)
				)
			)
			(stroke
				(width 0)
				(type default)
			)
			(fill no)
			(layer "F.CrtYd")
		)
		(fp_poly
			(pts
				(arc
					(start 0.6096 0)
					(mid -0.6096 0)
					(end 0.6096 0)
				)
			)
			(stroke
				(width 0)
				(type default)
			)
			(fill no)
			(layer "F.Fab")
		)
		(pad "1" smd circle
			(at 0 0)
			(size 0.7112 0.7112)
			(layers "F.Cu" "F.Mask" "F.Paste")
			(net "TP_GPIOD5")
		)
	)
	(footprint ""
		(layer "F.Cu")
		(at 19.4183 -178.3461)
		(property "Reference" "R692"
			(at 0 0 0)
			(layer "F.SilkS")
			(hide yes)
			(effects
				(font
					(size 1.27 1.27)
				)
			)
		)
		(property "Value" "1K33R3F-GP"
			(at -0.0254 -2.5146 0)
			(unlocked yes)
			(layer "F.Fab")
			(hide yes)
			(effects
				(font
					(size 1.016 1.016)
					(thickness 0.1524)
				)
			)
		)
		(property "Device Type" "R603H22"
			(at -0.0254 -4.0386 0)
			(unlocked yes)
			(layer "F.Fab")
			(hide yes)
			(effects
				(font
					(size 1.016 1.016)
					(thickness 0.1524)
				)
			)
		)
		(duplicate_pad_numbers_are_jumpers no)
		(fp_line
			(start -0.4826 0)
			(end -0.2032 0)
			(stroke
				(width 0.2032)
				(type default)
			)
			(layer "F.SilkS")
		)
		(fp_line
			(start 0.2032 0)
			(end 0.4826 0)
			(stroke
				(width 0.2032)
				(type default)
			)
			(layer "F.SilkS")
		)
		(fp_rect
			(start -0.5842 1.3335)
			(end 0.5842 -1.3335)
			(stroke
				(width 0)
				(type default)
			)
			(fill no)
			(layer "F.CrtYd")
		)
		(fp_rect
			(start -0.5842 1.3335)
			(end 0.5842 -1.3335)
			(stroke
				(width 0)
				(type default)
			)
			(fill no)
			(layer "F.Fab")
		)
		(pad "1" smd custom
			(at 0 -0.762)
			(size 0.2159 0.2159)
			(layers "F.Cu" "F.Mask" "F.Paste")
			(net "MB0_HS_ENABLE")
			(options
				(clearance outline)
				(anchor circle)
			)
			(primitives
				(gr_poly
					(pts
						(arc
							(start -0.3302 -0.4318)
							(mid -0.402042 -0.402042)
							(end -0.4318 -0.3302)
						)
						(arc
							(start -0.4318 0.3302)
							(mid -0.402042 0.402042)
							(end -0.3302 0.4318)
						)
						(arc
							(start 0.3302 0.4318)
							(mid 0.402042 0.402042)
							(end 0.4318 0.3302)
						)
						(arc
							(start 0.4318 -0.3302)
							(mid 0.402042 -0.402042)
							(end 0.3302 -0.4318)
						)
					)
					(width 0)
					(fill yes)
				)
			)
		)
		(pad "2" smd custom
			(at 0 0.762)
			(size 0.2159 0.2159)
			(layers "F.Cu" "F.Mask" "F.Paste")
			(net "GND")
			(options
				(clearance outline)
				(anchor circle)
			)
			(primitives
				(gr_poly
					(pts
						(arc
							(start -0.3302 -0.4318)
							(mid -0.402042 -0.402042)
							(end -0.4318 -0.3302)
						)
						(arc
							(start -0.4318 0.3302)
							(mid -0.402042 0.402042)
							(end -0.3302 0.4318)
						)
						(arc
							(start 0.3302 0.4318)
							(mid 0.402042 0.402042)
							(end 0.4318 0.3302)
						)
						(arc
							(start 0.4318 -0.3302)
							(mid 0.402042 -0.402042)
							(end 0.3302 -0.4318)
						)
					)
					(width 0)
					(fill yes)
				)
			)
		)
	)
)
